G04 ================== begin FILE IDENTIFICATION RECORD ==================*
G04 Layout Name:  9051_F0T_Panel_BD_Front_D_v02_20221209_1310.brd*
G04 Film Name:    ssb.art*
G04 File Format:  Gerber RS274X*
G04 File Origin:  Cadence Allegro 17.2-S081*
G04 Origin Date:  Mon Dec 12 15:51:17 2022*
G04 *
G04 Layer:  DRAWING FORMAT/TITLE_BLOCK_A*
G04 Layer:  BOARD GEOMETRY/DESIGN_OUTLINE*
G04 Layer:  BOARD GEOMETRY/CUTOUT*
G04 Layer:  DRAWING FORMAT/TITLE_BLOCK*
G04 Layer:  MANUFACTURING/TP_TEXT_BOTTOM*
G04 Layer:  REF DES/SILKSCREEN_BOTTOM*
G04 Layer:  PACKAGE GEOMETRY/SILKSCREEN_BOTTOM*
G04 Layer:  MANUFACTURING/PHOTOPLOT_OUTLINE*
G04 Layer:  DRAWING FORMAT/TITLE_DATA_SSB*
G04 Layer:  BOARD GEOMETRY/SILKSCREEN_BOTTOM*
G04 *
G04 Offset:    (0.00 0.00)*
G04 Mirror:    No*
G04 Mode:      Positive*
G04 Rotation:  0*
G04 FullContactRelief:  No*
G04 UndefLineWidth:     6.00*
G04 ================== end FILE IDENTIFICATION RECORD ====================*
%FSLAX25Y25*MOIN*%
%IR0*IPPOS*OFA0.00000B0.00000*MIA0B0*SFA1.00000B1.00000*%
%ADD10C,.01*%
%ADD11C,.006*%
G75*
%LPD*%
G75*
G36*
G01X48278Y162682D02*
X48778Y163232D01*
X44643Y167530D01*
X45132Y172960D01*
X48978Y176932D01*
X48728Y177632D01*
X48028Y177732D01*
X45307Y174904D01*
X45415Y176100D01*
X44175Y177100D01*
X43175Y177150D01*
X42225Y177600D01*
X40075D01*
X39525Y177350D01*
X38375Y176500D01*
X38175D01*
X37775Y176900D01*
X36975Y176800D01*
X36625Y176400D01*
Y175864D01*
X34828Y177732D01*
X34128Y177632D01*
X33878Y176932D01*
X36625Y174095D01*
Y173050D01*
X36875Y172750D01*
X37475D01*
X38071Y167383D01*
X37977Y167285D01*
X37925Y167250D01*
G03X37302Y166583I1089J-1641D01*
G01X34078Y163232D01*
X34578Y162682D01*
X35228Y162732D01*
X37222Y164791D01*
G03X40675Y164550I1792J818D01*
G01X44375D01*
X44502Y165960D01*
X47628Y162732D01*
X48278Y162682D01*
G37*
G36*
G01X48000Y162300D02*
X34850D01*
Y160000D01*
X48000D01*
Y162300D01*
G37*
%LPC*%
G75*
G36*
G01X41428Y170872D02*
X43794Y173331D01*
X43875Y174600D01*
X38975D01*
X39054Y173340D01*
X41428Y170872D01*
G37*
G36*
G01X42266Y170001D02*
X43499Y168719D01*
X43674Y171454D01*
X42266Y170001D01*
G37*
G36*
G01X39343Y168705D02*
X40590Y170001D01*
X39171Y171466D01*
X39343Y168705D01*
G37*
G36*
G01X39675Y167300D02*
G02X40975Y165950I-849J-2119D01*
G01X43325Y166000D01*
X43396Y167103D01*
X41428Y169135D01*
X39658Y167307D01*
X39675Y167300D01*
G37*
%LPD*%
G75*
G36*
G01X42775Y173550D02*
X40075D01*
Y172800D01*
X42775D01*
Y173550D01*
G37*
G54D10*
G01X14500Y147900D02*
X13400Y148500D01*
Y143500D01*
G01X15610Y162300D02*
G03I-2410J0D01*
G01X21000Y146200D02*
X15800D01*
X15900Y146900D01*
X16000Y147200D01*
X16200Y147600D01*
X16500Y148000D01*
X17000Y148400D01*
X17400Y148600D01*
X17700Y148700D01*
X18200Y148800D01*
X18600D01*
X19100Y148700D01*
X19400Y148600D01*
X19800Y148400D01*
X20200Y148100D01*
X20300Y148000D01*
X20600Y147600D01*
X20800Y147200D01*
X20900Y146900D01*
X21000Y146300D01*
Y146000D01*
X20900Y145500D01*
X20800Y145200D01*
X20600Y144800D01*
X20300Y144400D01*
X19800Y144000D01*
X19400Y143800D01*
X19100Y143700D01*
X18500Y143600D01*
X18400D01*
X17700Y143700D01*
X17400Y143800D01*
X17200Y143900D01*
X16600Y144300D01*
X16200Y144800D01*
G01X21700Y170000D02*
Y159900D01*
G01Y170000D02*
X19200D01*
G03Y165000I0J-2500D01*
G01X21700D01*
G01X15600Y170000D02*
Y159900D01*
G54D11*
G01X-117168Y-317735D02*
Y-322735D01*
G01X-118625Y-317735D02*
X-115711D01*
G01X-110801Y-322735D02*
X-113335D01*
Y-317735D01*
X-110801D01*
G01X-111815Y-320152D02*
X-113335D01*
G01X-108235Y-317735D02*
Y-322735D01*
X-105701D01*
G01X-101868Y-322902D02*
X-101995Y-322818D01*
Y-322652D01*
X-101868Y-322568D01*
X-101741Y-322652D01*
Y-322818D01*
X-101868Y-322902D01*
G01Y-320652D02*
X-101995Y-320568D01*
Y-320402D01*
X-101868Y-320318D01*
X-101741Y-320402D01*
Y-320568D01*
X-101868Y-320652D01*
G01X-97085Y-324402D02*
X-97718Y-323568D01*
X-98035Y-322735D01*
Y-319402D01*
X-97718Y-318568D01*
X-97085Y-317735D01*
G01X-91668D02*
X-92175Y-317902D01*
X-92555Y-318318D01*
X-92808Y-318818D01*
X-92998Y-319485D01*
X-93061Y-320235D01*
X-92998Y-320985D01*
X-92808Y-321652D01*
X-92555Y-322152D01*
X-92175Y-322568D01*
X-91668Y-322735D01*
X-91161Y-322568D01*
X-90781Y-322152D01*
X-90528Y-321652D01*
X-90338Y-320985D01*
X-90275Y-320235D01*
X-90338Y-319485D01*
X-90528Y-318818D01*
X-90781Y-318318D01*
X-91161Y-317902D01*
X-91668Y-317735D01*
G01X-87961Y-321735D02*
X-87581Y-322318D01*
X-87075Y-322652D01*
X-86505Y-322735D01*
X-85998Y-322652D01*
X-85491Y-322235D01*
X-85175Y-321735D01*
X-85111Y-321235D01*
X-85238Y-320652D01*
X-85681Y-320235D01*
X-86125Y-320068D01*
X-86695D01*
G01X-86125D02*
X-85745Y-319818D01*
X-85428Y-319402D01*
X-85301Y-318902D01*
X-85428Y-318402D01*
X-85745Y-317985D01*
X-86315Y-317735D01*
X-86885Y-317818D01*
X-87455Y-318152D01*
G01X-81151Y-324402D02*
X-80518Y-323568D01*
X-80201Y-322735D01*
Y-319402D01*
X-80518Y-318568D01*
X-81151Y-317735D01*
G01X-77761Y-321735D02*
X-77381Y-322318D01*
X-76875Y-322652D01*
X-76305Y-322735D01*
X-75798Y-322652D01*
X-75291Y-322235D01*
X-74975Y-321735D01*
X-74911Y-321235D01*
X-75038Y-320652D01*
X-75481Y-320235D01*
X-75925Y-320068D01*
X-76495D01*
G01X-75925D02*
X-75545Y-319818D01*
X-75228Y-319402D01*
X-75101Y-318902D01*
X-75228Y-318402D01*
X-75545Y-317985D01*
X-76115Y-317735D01*
X-76685Y-317818D01*
X-77255Y-318152D01*
G01X-72471Y-318568D02*
X-72091Y-318068D01*
X-71648Y-317818D01*
X-71141Y-317735D01*
X-70508Y-317902D01*
X-70065Y-318318D01*
X-69938Y-318818D01*
X-70001Y-319318D01*
X-70255Y-319735D01*
X-71521Y-320568D01*
X-72091Y-321152D01*
X-72471Y-321985D01*
X-72598Y-322735D01*
X-69938D01*
G01X-66295D02*
X-66168Y-321652D01*
X-65978Y-320735D01*
X-65725Y-319902D01*
X-65408Y-318985D01*
X-64901Y-317735D01*
X-67435D01*
G01X-61891Y-321068D02*
X-60245D01*
G01X-57171Y-318568D02*
X-56791Y-318068D01*
X-56348Y-317818D01*
X-55841Y-317735D01*
X-55208Y-317902D01*
X-54765Y-318318D01*
X-54638Y-318818D01*
X-54701Y-319318D01*
X-54955Y-319735D01*
X-56221Y-320568D01*
X-56791Y-321152D01*
X-57171Y-321985D01*
X-57298Y-322735D01*
X-54638D01*
G01X-52261Y-321735D02*
X-51881Y-322318D01*
X-51375Y-322652D01*
X-50805Y-322735D01*
X-50298Y-322652D01*
X-49791Y-322235D01*
X-49475Y-321735D01*
X-49411Y-321235D01*
X-49538Y-320652D01*
X-49981Y-320235D01*
X-50425Y-320068D01*
X-50995D01*
G01X-50425D02*
X-50045Y-319818D01*
X-49728Y-319402D01*
X-49601Y-318902D01*
X-49728Y-318402D01*
X-50045Y-317985D01*
X-50615Y-317735D01*
X-51185Y-317818D01*
X-51755Y-318152D01*
G01X-45008Y-322735D02*
Y-317735D01*
X-47351Y-321318D01*
X-44185D01*
G01X-42061Y-321985D02*
X-41681Y-322402D01*
X-41238Y-322652D01*
X-40668Y-322735D01*
X-40098Y-322568D01*
X-39655Y-322235D01*
X-39338Y-321652D01*
X-39275Y-320985D01*
X-39401Y-320318D01*
X-39718Y-319902D01*
X-40161Y-319568D01*
X-40605Y-319485D01*
X-41048Y-319568D01*
X-41618Y-319902D01*
X-41428Y-317735D01*
X-39718D01*
G01X-31671Y-322735D02*
Y-317735D01*
X-29265D01*
G01X-30151Y-320152D02*
X-31671D01*
G01X-26951Y-322735D02*
X-25368Y-317735D01*
X-23785Y-322735D01*
G01X-24355Y-320985D02*
X-26381D01*
G01X-21598Y-322735D02*
X-18938Y-317735D01*
G01X-21598D02*
X-18938Y-322735D01*
G01X-15168Y-322902D02*
X-15295Y-322818D01*
Y-322652D01*
X-15168Y-322568D01*
X-15041Y-322652D01*
Y-322818D01*
X-15168Y-322902D01*
G01Y-320652D02*
X-15295Y-320568D01*
Y-320402D01*
X-15168Y-320318D01*
X-15041Y-320402D01*
Y-320568D01*
X-15168Y-320652D01*
G01X-10385Y-324402D02*
X-11018Y-323568D01*
X-11335Y-322735D01*
Y-319402D01*
X-11018Y-318568D01*
X-10385Y-317735D01*
G01X-4968D02*
X-5475Y-317902D01*
X-5855Y-318318D01*
X-6108Y-318818D01*
X-6298Y-319485D01*
X-6361Y-320235D01*
X-6298Y-320985D01*
X-6108Y-321652D01*
X-5855Y-322152D01*
X-5475Y-322568D01*
X-4968Y-322735D01*
X-4461Y-322568D01*
X-4081Y-322152D01*
X-3828Y-321652D01*
X-3638Y-320985D01*
X-3575Y-320235D01*
X-3638Y-319485D01*
X-3828Y-318818D01*
X-4081Y-318318D01*
X-4461Y-317902D01*
X-4968Y-317735D01*
G01X-1261Y-321735D02*
X-881Y-322318D01*
X-375Y-322652D01*
X195Y-322735D01*
X702Y-322652D01*
X1209Y-322235D01*
X1525Y-321735D01*
X1589Y-321235D01*
X1462Y-320652D01*
X1019Y-320235D01*
X575Y-320068D01*
X5D01*
G01X575D02*
X955Y-319818D01*
X1272Y-319402D01*
X1399Y-318902D01*
X1272Y-318402D01*
X955Y-317985D01*
X385Y-317735D01*
X-185Y-317818D01*
X-755Y-318152D01*
G01X5549Y-324402D02*
X6182Y-323568D01*
X6499Y-322735D01*
Y-319402D01*
X6182Y-318568D01*
X5549Y-317735D01*
G01X8939Y-321735D02*
X9319Y-322318D01*
X9825Y-322652D01*
X10395Y-322735D01*
X10902Y-322652D01*
X11409Y-322235D01*
X11725Y-321735D01*
X11789Y-321235D01*
X11662Y-320652D01*
X11219Y-320235D01*
X10775Y-320068D01*
X10205D01*
G01X10775D02*
X11155Y-319818D01*
X11472Y-319402D01*
X11599Y-318902D01*
X11472Y-318402D01*
X11155Y-317985D01*
X10585Y-317735D01*
X10015Y-317818D01*
X9445Y-318152D01*
G01X14355Y-322152D02*
X14799Y-322568D01*
X15305Y-322735D01*
X15812Y-322568D01*
X16255Y-322068D01*
X16572Y-321318D01*
X16699Y-320568D01*
Y-319652D01*
X16572Y-318902D01*
X16255Y-318235D01*
X15875Y-317902D01*
X15432Y-317735D01*
X14925Y-317902D01*
X14545Y-318235D01*
X14292Y-318735D01*
X14165Y-319402D01*
X14292Y-319985D01*
X14609Y-320568D01*
X14989Y-320902D01*
X15432Y-320985D01*
X15939Y-320818D01*
X16319Y-320402D01*
X16699Y-319652D01*
G01X20405Y-322735D02*
X20532Y-321652D01*
X20722Y-320735D01*
X20975Y-319902D01*
X21292Y-318985D01*
X21799Y-317735D01*
X19265D01*
G01X24809Y-321068D02*
X26455D01*
G01X29339Y-321735D02*
X29719Y-322318D01*
X30225Y-322652D01*
X30795Y-322735D01*
X31302Y-322652D01*
X31809Y-322235D01*
X32125Y-321735D01*
X32189Y-321235D01*
X32062Y-320652D01*
X31619Y-320235D01*
X31175Y-320068D01*
X30605D01*
G01X31175D02*
X31555Y-319818D01*
X31872Y-319402D01*
X31999Y-318902D01*
X31872Y-318402D01*
X31555Y-317985D01*
X30985Y-317735D01*
X30415Y-317818D01*
X29845Y-318152D01*
G01X34629Y-320652D02*
X35072Y-320068D01*
X35452Y-319735D01*
X35959Y-319568D01*
X36402Y-319735D01*
X36719Y-320068D01*
X36972Y-320568D01*
X37035Y-321152D01*
X36972Y-321652D01*
X36719Y-322152D01*
X36339Y-322568D01*
X35895Y-322735D01*
X35389Y-322568D01*
X34945Y-322068D01*
X34692Y-321318D01*
X34629Y-320485D01*
X34755Y-319402D01*
X34945Y-318818D01*
X35262Y-318235D01*
X35705Y-317818D01*
X36149Y-317735D01*
X36592Y-317902D01*
X36909Y-318318D01*
G01X40932Y-322735D02*
Y-317735D01*
X40172Y-318735D01*
G01Y-322735D02*
X41692D01*
G01X46792D02*
Y-317735D01*
X44449Y-321318D01*
X47615D01*
G01X-129168Y-252735D02*
Y-327735D01*
X370832D01*
Y-252735D01*
X-129168D01*
G01X150394Y283264D02*
Y307087D01*
G03X142520Y314961I-7874J0D01*
G01X129331D01*
G02X121457Y322835I0J7874D01*
G01Y331299D01*
G03X113583Y339173I-7874J0D01*
G01X58465D01*
G03X50591Y331299I0J-7874D01*
G01Y322835D01*
G02X42717Y314961I-7874J0D01*
G01X12205D01*
G03X4331Y307087I0J-7874D01*
G01Y283264D01*
G02X2165Y277840I-7875J0D01*
G03X0Y272417I5709J-5423D01*
G01Y7874D01*
G03X7874Y0I7874J0D01*
G01X146850D01*
G03X154724Y7874I0J7874D01*
G01Y272417D01*
G03X152559Y277840I-7874J0D01*
G02X150394Y283264I5710J5423D01*
G01X24016Y50787D02*
G02Y66535I0J7874D01*
G02Y50787I0J-7874D01*
G01X33640Y287042D02*
G03X31890Y282093I6124J-4949D01*
G01Y279449D01*
G02X20079I-5905J0D01*
G01Y282093D01*
G03X18329Y287042I-7874J0D01*
G02X33640I7656J6187D01*
G01X65832Y-252735D02*
Y-327735D01*
G01Y-302735D02*
X168832D01*
Y-277735D01*
G01X65832D02*
X168832D01*
G01X129134Y239669D02*
G02Y255417I0J7874D01*
G02Y239669I0J-7874D01*
G01X143876Y51018D02*
G03X142126Y46069I6124J-4949D01*
G01Y43425D01*
G02X130315I-5906J0D01*
G01Y46069D01*
G03X128565Y51018I-7874J0D01*
G02X143876I7655J6187D01*
G01X176339Y-312735D02*
Y-307735D01*
X177605D01*
X178112Y-307985D01*
X178492Y-308318D01*
X178809Y-308818D01*
X179062Y-309402D01*
X179125Y-310235D01*
X179062Y-311068D01*
X178809Y-311652D01*
X178492Y-312152D01*
X178112Y-312485D01*
X177605Y-312735D01*
X176339D01*
G01X181249D02*
X182832Y-307735D01*
X184415Y-312735D01*
G01X183845Y-310985D02*
X181819D01*
G01X187932Y-307735D02*
Y-312735D01*
G01X186475Y-307735D02*
X189389D01*
G01X194299Y-312735D02*
X191765D01*
Y-307735D01*
X194299D01*
G01X193285Y-310152D02*
X191765D01*
G01X198132Y-312902D02*
X198005Y-312818D01*
Y-312652D01*
X198132Y-312568D01*
X198259Y-312652D01*
Y-312818D01*
X198132Y-312902D01*
G01Y-310652D02*
X198005Y-310568D01*
Y-310402D01*
X198132Y-310318D01*
X198259Y-310402D01*
Y-310568D01*
X198132Y-310652D01*
G01X170832Y-252735D02*
Y-327735D01*
G01X168832Y-252735D02*
Y-327735D01*
G01X170832Y-302735D02*
X370832D01*
G01X176465Y-287735D02*
Y-282735D01*
X177985D01*
X178492Y-282985D01*
X178872Y-283568D01*
X178999Y-284235D01*
X178872Y-284902D01*
X178555Y-285402D01*
X177985Y-285652D01*
X176465D01*
G01X181692Y-287902D02*
X183972Y-282735D01*
G01X186475Y-287735D02*
Y-282735D01*
X189389Y-287735D01*
Y-282735D01*
G01X193032Y-287902D02*
X192905Y-287818D01*
Y-287652D01*
X193032Y-287568D01*
X193159Y-287652D01*
Y-287818D01*
X193032Y-287902D01*
G01Y-285652D02*
X192905Y-285568D01*
Y-285402D01*
X193032Y-285318D01*
X193159Y-285402D01*
Y-285568D01*
X193032Y-285652D01*
G01X170832Y-277735D02*
X370832D01*
G01X176465Y-262735D02*
Y-257735D01*
X177985D01*
X178492Y-257985D01*
X178872Y-258568D01*
X178999Y-259235D01*
X178872Y-259902D01*
X178555Y-260402D01*
X177985Y-260652D01*
X176465D01*
G01X181565Y-262735D02*
Y-257735D01*
X183149D01*
X183655Y-257985D01*
X183972Y-258318D01*
X184099Y-258985D01*
X183972Y-259652D01*
X183592Y-260068D01*
X183149Y-260318D01*
X181565D01*
G01X183149D02*
X184099Y-262735D01*
G01X187932D02*
X187425Y-262652D01*
X186982Y-262318D01*
X186602Y-261818D01*
X186349Y-261235D01*
X186222Y-260568D01*
Y-259902D01*
X186349Y-259235D01*
X186602Y-258652D01*
X186982Y-258152D01*
X187425Y-257818D01*
X187932Y-257735D01*
X188439Y-257818D01*
X188882Y-258152D01*
X189262Y-258652D01*
X189515Y-259235D01*
X189642Y-259902D01*
Y-260568D01*
X189515Y-261235D01*
X189262Y-261818D01*
X188882Y-262318D01*
X188439Y-262652D01*
X187932Y-262735D01*
G01X191765Y-261735D02*
X192082Y-262235D01*
X192462Y-262568D01*
X192905Y-262735D01*
X193412Y-262568D01*
X193792Y-262235D01*
X194172Y-261735D01*
X194299Y-261068D01*
Y-257735D01*
G01X199399Y-262735D02*
X196865D01*
Y-257735D01*
X199399D01*
G01X198385Y-260152D02*
X196865D01*
G01X204625Y-258152D02*
X204245Y-257902D01*
X203802Y-257735D01*
X203295D01*
X202725Y-257985D01*
X202282Y-258402D01*
X201965Y-258902D01*
X201712Y-259735D01*
X201649Y-260485D01*
X201775Y-261235D01*
X201965Y-261735D01*
X202345Y-262235D01*
X202789Y-262568D01*
X203232Y-262735D01*
X203675D01*
X204119Y-262568D01*
X204499Y-262318D01*
X204815Y-261985D01*
G01X208332Y-257735D02*
Y-262735D01*
G01X206875Y-257735D02*
X209789D01*
G01X213432Y-262902D02*
X213305Y-262818D01*
Y-262652D01*
X213432Y-262568D01*
X213559Y-262652D01*
Y-262818D01*
X213432Y-262902D01*
G01Y-260652D02*
X213305Y-260568D01*
Y-260402D01*
X213432Y-260318D01*
X213559Y-260402D01*
Y-260568D01*
X213432Y-260652D01*
G01X283832Y-302735D02*
Y-327735D01*
G01X288465Y-305235D02*
Y-310235D01*
X290999D01*
G01X294072Y-305235D02*
X295592D01*
G01X294832D02*
Y-310235D01*
G01X294072D02*
X295592D01*
G01X300439Y-307568D02*
X300692Y-307318D01*
X300882Y-306902D01*
X301009Y-306318D01*
X300882Y-305818D01*
X300629Y-305485D01*
X300185Y-305235D01*
X298475D01*
Y-310235D01*
X300565D01*
X301009Y-309902D01*
X301262Y-309402D01*
X301389Y-308818D01*
X301262Y-308235D01*
X300882Y-307735D01*
X300439Y-307568D01*
X298475D01*
G01X305032Y-310402D02*
X304905Y-310318D01*
Y-310152D01*
X305032Y-310068D01*
X305159Y-310152D01*
Y-310318D01*
X305032Y-310402D01*
G01Y-308152D02*
X304905Y-308068D01*
Y-307902D01*
X305032Y-307818D01*
X305159Y-307902D01*
Y-308068D01*
X305032Y-308152D01*
G01X328832Y-302735D02*
Y-327735D01*
G01X332732Y-305235D02*
Y-310235D01*
G01X331275Y-305235D02*
X334189D01*
G01X337832Y-310235D02*
X337452Y-310152D01*
X337072Y-309818D01*
X336819Y-309235D01*
X336692Y-308568D01*
X336819Y-307902D01*
X337072Y-307318D01*
X337452Y-306985D01*
X337832Y-306902D01*
X338212Y-306985D01*
X338592Y-307318D01*
X338845Y-307902D01*
X338909Y-308568D01*
X338845Y-309235D01*
X338592Y-309818D01*
X338212Y-310152D01*
X337832Y-310235D01*
G01X342932D02*
X342552Y-310152D01*
X342172Y-309818D01*
X341919Y-309235D01*
X341792Y-308568D01*
X341919Y-307902D01*
X342172Y-307318D01*
X342552Y-306985D01*
X342932Y-306902D01*
X343312Y-306985D01*
X343692Y-307318D01*
X343945Y-307902D01*
X344009Y-308568D01*
X343945Y-309235D01*
X343692Y-309818D01*
X343312Y-310152D01*
X342932Y-310235D01*
G01X348032D02*
Y-305235D01*
G01X353132Y-310402D02*
X353005Y-310318D01*
Y-310152D01*
X353132Y-310068D01*
X353259Y-310152D01*
Y-310318D01*
X353132Y-310402D01*
G01Y-308152D02*
X353005Y-308068D01*
Y-307902D01*
X353132Y-307818D01*
X353259Y-307902D01*
Y-308068D01*
X353132Y-308152D01*
G01X328832Y-277735D02*
Y-302735D01*
G01X331465Y-285235D02*
Y-280235D01*
X333049D01*
X333555Y-280485D01*
X333872Y-280818D01*
X333999Y-281485D01*
X333872Y-282152D01*
X333492Y-282568D01*
X333049Y-282818D01*
X331465D01*
G01X333049D02*
X333999Y-285235D01*
G01X339099D02*
X336565D01*
Y-280235D01*
X339099D01*
G01X338085Y-282652D02*
X336565D01*
G01X341349Y-280235D02*
X342932Y-285235D01*
X344515Y-280235D01*
G01X348032Y-285402D02*
X347905Y-285318D01*
Y-285152D01*
X348032Y-285068D01*
X348159Y-285152D01*
Y-285318D01*
X348032Y-285402D01*
G01Y-283152D02*
X347905Y-283068D01*
Y-282902D01*
X348032Y-282818D01*
X348159Y-282902D01*
Y-283068D01*
X348032Y-283152D01*
G01X351592Y-329435D02*
X351672Y-329360D01*
X351732Y-329235D01*
X351772Y-329060D01*
X351732Y-328910D01*
X351652Y-328810D01*
X351512Y-328735D01*
X350972D01*
Y-330235D01*
X351632D01*
X351772Y-330135D01*
X351852Y-329985D01*
X351892Y-329810D01*
X351852Y-329635D01*
X351732Y-329485D01*
X351592Y-329435D01*
X350972D01*
G01X352992Y-330235D02*
Y-329235D01*
G01Y-329410D02*
X352912Y-329310D01*
X352792Y-329260D01*
X352652Y-329235D01*
X352512Y-329285D01*
X352392Y-329385D01*
X352312Y-329535D01*
X352272Y-329735D01*
X352312Y-329935D01*
X352392Y-330085D01*
X352512Y-330185D01*
X352652Y-330235D01*
X352792Y-330210D01*
X352912Y-330135D01*
X352992Y-330035D01*
G01X353532Y-330060D02*
X353632Y-330160D01*
X353772Y-330235D01*
X353892D01*
X354012Y-330185D01*
X354092Y-330110D01*
X354132Y-330010D01*
X354112Y-329860D01*
X354032Y-329785D01*
X353672Y-329635D01*
X353592Y-329460D01*
X353632Y-329335D01*
X353712Y-329260D01*
X353832Y-329235D01*
X353952Y-329260D01*
X354072Y-329335D01*
G01X354732Y-329560D02*
X355372D01*
X355312Y-329385D01*
X355212Y-329285D01*
X355072Y-329235D01*
X354932Y-329260D01*
X354812Y-329335D01*
X354732Y-329510D01*
X354692Y-329660D01*
Y-329810D01*
X354732Y-329960D01*
X354832Y-330110D01*
X354952Y-330210D01*
X355092Y-330235D01*
X355232Y-330185D01*
X355372Y-330035D01*
G01X355872Y-330235D02*
Y-328735D01*
G01Y-329485D02*
X355972Y-329335D01*
X356092Y-329260D01*
X356212Y-329235D01*
X356392Y-329285D01*
X356512Y-329385D01*
X356592Y-329560D01*
Y-329760D01*
X356552Y-329960D01*
X356472Y-330110D01*
X356332Y-330210D01*
X356212Y-330235D01*
X356092Y-330210D01*
X355972Y-330135D01*
X355872Y-330010D01*
G01X357432Y-330235D02*
X357312Y-330210D01*
X357192Y-330110D01*
X357112Y-329935D01*
X357072Y-329735D01*
X357112Y-329535D01*
X357192Y-329360D01*
X357312Y-329260D01*
X357432Y-329235D01*
X357552Y-329260D01*
X357672Y-329360D01*
X357752Y-329535D01*
X357772Y-329735D01*
X357752Y-329935D01*
X357672Y-330110D01*
X357552Y-330210D01*
X357432Y-330235D01*
G01X358992D02*
Y-329235D01*
G01Y-329410D02*
X358912Y-329310D01*
X358792Y-329260D01*
X358652Y-329235D01*
X358512Y-329285D01*
X358392Y-329385D01*
X358312Y-329535D01*
X358272Y-329735D01*
X358312Y-329935D01*
X358392Y-330085D01*
X358512Y-330185D01*
X358652Y-330235D01*
X358792Y-330210D01*
X358912Y-330135D01*
X358992Y-330035D01*
G01X359552Y-330235D02*
Y-329235D01*
G01Y-329435D02*
X359652Y-329335D01*
X359752Y-329260D01*
X359892Y-329235D01*
X359992Y-329260D01*
X360112Y-329335D01*
G01X361392Y-328735D02*
Y-330235D01*
G01Y-330010D02*
X361312Y-330135D01*
X361192Y-330210D01*
X361052Y-330235D01*
X360892Y-330185D01*
X360772Y-330060D01*
X360692Y-329910D01*
X360672Y-329735D01*
X360692Y-329560D01*
X360772Y-329410D01*
X360892Y-329285D01*
X361052Y-329235D01*
X361192Y-329260D01*
X361292Y-329310D01*
X361392Y-329410D01*
G01X363032Y-330235D02*
Y-328735D01*
X363532D01*
X363692Y-328810D01*
X363792Y-328910D01*
X363832Y-329110D01*
X363792Y-329310D01*
X363672Y-329435D01*
X363532Y-329510D01*
X363032D01*
G01X363532D02*
X363832Y-330235D01*
G01X364332Y-329560D02*
X364972D01*
X364912Y-329385D01*
X364812Y-329285D01*
X364672Y-329235D01*
X364532Y-329260D01*
X364412Y-329335D01*
X364332Y-329510D01*
X364292Y-329660D01*
Y-329810D01*
X364332Y-329960D01*
X364432Y-330110D01*
X364552Y-330210D01*
X364692Y-330235D01*
X364832Y-330185D01*
X364972Y-330035D01*
G01X365472Y-329235D02*
X365832Y-330235D01*
X366192Y-329235D01*
G01X367032Y-330285D02*
X366992Y-330260D01*
Y-330210D01*
X367032Y-330185D01*
X367072Y-330210D01*
Y-330260D01*
X367032Y-330285D01*
G01X368192Y-330235D02*
X368232Y-329910D01*
X368292Y-329635D01*
X368372Y-329385D01*
X368472Y-329110D01*
X368632Y-328735D01*
X367832D01*
G01X369592Y-329435D02*
X369672Y-329360D01*
X369732Y-329235D01*
X369772Y-329060D01*
X369732Y-328910D01*
X369652Y-328810D01*
X369512Y-328735D01*
X368972D01*
Y-330235D01*
X369632D01*
X369772Y-330135D01*
X369852Y-329985D01*
X369892Y-329810D01*
X369852Y-329635D01*
X369732Y-329485D01*
X369592Y-329435D01*
X368972D01*
G01X-247901Y-428634D02*
Y1008173D01*
X2091018D01*
Y-428634D01*
X-247901D01*
G01X-115095Y-307460D02*
X-115565Y-307145D01*
X-116113Y-306935D01*
X-116740D01*
X-117445Y-307250D01*
X-117993Y-307775D01*
X-118385Y-308405D01*
X-118698Y-309455D01*
X-118776Y-310400D01*
X-118620Y-311345D01*
X-118385Y-311975D01*
X-117915Y-312605D01*
X-117366Y-313025D01*
X-116818Y-313235D01*
X-116270D01*
X-115721Y-313025D01*
X-115251Y-312710D01*
X-114860Y-312290D01*
G01X-111458Y-306935D02*
X-109578D01*
G01X-110518D02*
Y-313235D01*
G01X-111458D02*
X-109578D01*
G01X-104218Y-306935D02*
Y-313235D01*
G01X-106020Y-306935D02*
X-102416D01*
G01X-97918Y-313235D02*
Y-310400D01*
X-99485Y-306935D01*
G01X-96351D02*
X-97918Y-310400D01*
G01X-87041Y-311975D02*
X-86571Y-312710D01*
X-85945Y-313130D01*
X-85240Y-313235D01*
X-84613Y-313130D01*
X-83986Y-312605D01*
X-83595Y-311975D01*
X-83516Y-311345D01*
X-83673Y-310610D01*
X-84221Y-310085D01*
X-84770Y-309875D01*
X-85475D01*
G01X-84770D02*
X-84300Y-309560D01*
X-83908Y-309035D01*
X-83751Y-308405D01*
X-83908Y-307775D01*
X-84300Y-307250D01*
X-85005Y-306935D01*
X-85710Y-307040D01*
X-86415Y-307460D01*
G01X-80741Y-311975D02*
X-80271Y-312710D01*
X-79645Y-313130D01*
X-78940Y-313235D01*
X-78313Y-313130D01*
X-77686Y-312605D01*
X-77295Y-311975D01*
X-77216Y-311345D01*
X-77373Y-310610D01*
X-77921Y-310085D01*
X-78470Y-309875D01*
X-79175D01*
G01X-78470D02*
X-78000Y-309560D01*
X-77608Y-309035D01*
X-77451Y-308405D01*
X-77608Y-307775D01*
X-78000Y-307250D01*
X-78705Y-306935D01*
X-79410Y-307040D01*
X-80115Y-307460D01*
G01X-74441Y-311975D02*
X-73971Y-312710D01*
X-73345Y-313130D01*
X-72640Y-313235D01*
X-72013Y-313130D01*
X-71386Y-312605D01*
X-70995Y-311975D01*
X-70916Y-311345D01*
X-71073Y-310610D01*
X-71621Y-310085D01*
X-72170Y-309875D01*
X-72875D01*
G01X-72170D02*
X-71700Y-309560D01*
X-71308Y-309035D01*
X-71151Y-308405D01*
X-71308Y-307775D01*
X-71700Y-307250D01*
X-72405Y-306935D01*
X-73110Y-307040D01*
X-73815Y-307460D01*
G01X-66575Y-313235D02*
X-66418Y-311870D01*
X-66183Y-310715D01*
X-65870Y-309665D01*
X-65478Y-308510D01*
X-64851Y-306935D01*
X-67985D01*
G01X-60275Y-313235D02*
X-60118Y-311870D01*
X-59883Y-310715D01*
X-59570Y-309665D01*
X-59178Y-308510D01*
X-58551Y-306935D01*
X-61685D01*
G01X-53975Y-314390D02*
X-53661Y-313025D01*
G01X-47518Y-306935D02*
Y-313235D01*
G01X-49320Y-306935D02*
X-45716D01*
G01X-43176Y-313235D02*
X-41218Y-306935D01*
X-39260Y-313235D01*
G01X-39965Y-311030D02*
X-42471D01*
G01X-35858Y-306935D02*
X-33978D01*
G01X-34918D02*
Y-313235D01*
G01X-35858D02*
X-33978D01*
G01X-30968Y-306935D02*
X-29871Y-313235D01*
X-28618Y-306935D01*
X-27365Y-313235D01*
X-26268Y-306935D01*
G01X-24276Y-313235D02*
X-22318Y-306935D01*
X-20360Y-313235D01*
G01X-21065Y-311030D02*
X-23571D01*
G01X-17820Y-313235D02*
Y-306935D01*
X-14216Y-313235D01*
Y-306935D01*
G01X-3810Y-315335D02*
X-4593Y-314285D01*
X-4985Y-313235D01*
Y-309035D01*
X-4593Y-307985D01*
X-3810Y-306935D01*
G01X7615Y-313235D02*
Y-306935D01*
X9574D01*
X10200Y-307250D01*
X10592Y-307670D01*
X10749Y-308510D01*
X10592Y-309350D01*
X10122Y-309875D01*
X9574Y-310190D01*
X7615D01*
G01X9574D02*
X10749Y-313235D01*
G01X15482Y-313445D02*
X15325Y-313340D01*
Y-313130D01*
X15482Y-313025D01*
X15639Y-313130D01*
Y-313340D01*
X15482Y-313445D01*
G01X21782Y-313235D02*
X21155Y-313130D01*
X20607Y-312710D01*
X20137Y-312080D01*
X19824Y-311345D01*
X19667Y-310505D01*
Y-309665D01*
X19824Y-308825D01*
X20137Y-308090D01*
X20607Y-307460D01*
X21155Y-307040D01*
X21782Y-306935D01*
X22409Y-307040D01*
X22957Y-307460D01*
X23427Y-308090D01*
X23740Y-308825D01*
X23897Y-309665D01*
Y-310505D01*
X23740Y-311345D01*
X23427Y-312080D01*
X22957Y-312710D01*
X22409Y-313130D01*
X21782Y-313235D01*
G01X28082Y-313445D02*
X27925Y-313340D01*
Y-313130D01*
X28082Y-313025D01*
X28239Y-313130D01*
Y-313340D01*
X28082Y-313445D01*
G01X36105Y-307460D02*
X35635Y-307145D01*
X35087Y-306935D01*
X34460D01*
X33755Y-307250D01*
X33207Y-307775D01*
X32815Y-308405D01*
X32502Y-309455D01*
X32424Y-310400D01*
X32580Y-311345D01*
X32815Y-311975D01*
X33285Y-312605D01*
X33834Y-313025D01*
X34382Y-313235D01*
X34930D01*
X35479Y-313025D01*
X35949Y-312710D01*
X36340Y-312290D01*
G01X40682Y-313445D02*
X40525Y-313340D01*
Y-313130D01*
X40682Y-313025D01*
X40839Y-313130D01*
Y-313340D01*
X40682Y-313445D01*
G01X47374Y-315335D02*
X48157Y-314285D01*
X48549Y-313235D01*
Y-309035D01*
X48157Y-307985D01*
X47374Y-306935D01*
G01X-118620Y-293235D02*
Y-286935D01*
X-115016Y-293235D01*
Y-286935D01*
G01X-110518Y-293235D02*
X-111145Y-293130D01*
X-111693Y-292710D01*
X-112163Y-292080D01*
X-112476Y-291345D01*
X-112633Y-290505D01*
Y-289665D01*
X-112476Y-288825D01*
X-112163Y-288090D01*
X-111693Y-287460D01*
X-111145Y-287040D01*
X-110518Y-286935D01*
X-109891Y-287040D01*
X-109343Y-287460D01*
X-108873Y-288090D01*
X-108560Y-288825D01*
X-108403Y-289665D01*
Y-290505D01*
X-108560Y-291345D01*
X-108873Y-292080D01*
X-109343Y-292710D01*
X-109891Y-293130D01*
X-110518Y-293235D01*
G01X-104218Y-293445D02*
X-104375Y-293340D01*
Y-293130D01*
X-104218Y-293025D01*
X-104061Y-293130D01*
Y-293340D01*
X-104218Y-293445D01*
G01X-99406Y-287985D02*
X-98936Y-287355D01*
X-98388Y-287040D01*
X-97761Y-286935D01*
X-96978Y-287145D01*
X-96430Y-287670D01*
X-96273Y-288300D01*
X-96351Y-288930D01*
X-96665Y-289455D01*
X-98231Y-290505D01*
X-98936Y-291240D01*
X-99406Y-292290D01*
X-99563Y-293235D01*
X-96273D01*
G01X-91618D02*
Y-286935D01*
X-92558Y-288195D01*
G01Y-293235D02*
X-90678D01*
G01X-85318D02*
Y-286935D01*
X-86258Y-288195D01*
G01Y-293235D02*
X-84378D01*
G01X-79175Y-294390D02*
X-78861Y-293025D01*
G01X-75068Y-286935D02*
X-73971Y-293235D01*
X-72718Y-286935D01*
X-71465Y-293235D01*
X-70368Y-286935D01*
G01X-64851Y-293235D02*
X-67985D01*
Y-286935D01*
X-64851D01*
G01X-66105Y-289980D02*
X-67985D01*
G01X-61920Y-293235D02*
Y-286935D01*
X-58316Y-293235D01*
Y-286935D01*
G01X-55463Y-293235D02*
Y-286935D01*
G01X-52173D02*
Y-293235D01*
G01Y-290085D02*
X-55463D01*
G01X-49241Y-286935D02*
Y-291450D01*
X-48928Y-292395D01*
X-48301Y-293025D01*
X-47518Y-293235D01*
X-46735Y-293025D01*
X-46108Y-292395D01*
X-45795Y-291450D01*
Y-286935D01*
G01X-43176Y-293235D02*
X-41218Y-286935D01*
X-39260Y-293235D01*
G01X-39965Y-291030D02*
X-42471D01*
G01X-30106Y-287985D02*
X-29636Y-287355D01*
X-29088Y-287040D01*
X-28461Y-286935D01*
X-27678Y-287145D01*
X-27130Y-287670D01*
X-26973Y-288300D01*
X-27051Y-288930D01*
X-27365Y-289455D01*
X-28931Y-290505D01*
X-29636Y-291240D01*
X-30106Y-292290D01*
X-30263Y-293235D01*
X-26973D01*
G01X-24120D02*
Y-286935D01*
X-20516Y-293235D01*
Y-286935D01*
G01X-17741Y-293235D02*
Y-286935D01*
X-16175D01*
X-15548Y-287250D01*
X-15078Y-287670D01*
X-14686Y-288300D01*
X-14373Y-289035D01*
X-14295Y-290085D01*
X-14373Y-291135D01*
X-14686Y-291870D01*
X-15078Y-292500D01*
X-15548Y-292920D01*
X-16175Y-293235D01*
X-17741D01*
G01X-4985D02*
Y-286935D01*
X-3026D01*
X-2400Y-287250D01*
X-2008Y-287670D01*
X-1851Y-288510D01*
X-2008Y-289350D01*
X-2478Y-289875D01*
X-3026Y-290190D01*
X-4985D01*
G01X-3026D02*
X-1851Y-293235D01*
G01X1159D02*
Y-286935D01*
X2725D01*
X3352Y-287250D01*
X3822Y-287670D01*
X4214Y-288300D01*
X4527Y-289035D01*
X4605Y-290085D01*
X4527Y-291135D01*
X4214Y-291870D01*
X3822Y-292500D01*
X3352Y-292920D01*
X2725Y-293235D01*
X1159D01*
G01X9182Y-293445D02*
X9025Y-293340D01*
Y-293130D01*
X9182Y-293025D01*
X9339Y-293130D01*
Y-293340D01*
X9182Y-293445D01*
G01X-116348Y-300085D02*
X-114781D01*
Y-301975D01*
X-115251Y-302605D01*
X-115800Y-303025D01*
X-116583Y-303235D01*
X-117366Y-303025D01*
X-117915Y-302605D01*
X-118385Y-301975D01*
X-118698Y-301240D01*
X-118855Y-300400D01*
Y-299665D01*
X-118698Y-299035D01*
X-118385Y-298300D01*
X-117915Y-297670D01*
X-117445Y-297250D01*
X-116818Y-296935D01*
X-116270D01*
X-115643Y-297145D01*
X-115173Y-297565D01*
G01X-112241Y-296935D02*
Y-301450D01*
X-111928Y-302395D01*
X-111301Y-303025D01*
X-110518Y-303235D01*
X-109735Y-303025D01*
X-109108Y-302395D01*
X-108795Y-301450D01*
Y-296935D01*
G01X-105158D02*
X-103278D01*
G01X-104218D02*
Y-303235D01*
G01X-105158D02*
X-103278D01*
G01X-99563Y-302395D02*
X-98936Y-302920D01*
X-98231Y-303235D01*
X-97605D01*
X-96978Y-302920D01*
X-96508Y-302395D01*
X-96273Y-301660D01*
X-96430Y-300925D01*
X-96821Y-300295D01*
X-97526Y-299875D01*
X-98466Y-299665D01*
X-99015Y-299245D01*
X-99250Y-298510D01*
X-99093Y-297775D01*
X-98701Y-297250D01*
X-98153Y-296935D01*
X-97605D01*
X-97056Y-297145D01*
X-96586Y-297670D01*
G01X-93263Y-303235D02*
Y-296935D01*
G01X-89973D02*
Y-303235D01*
G01Y-300085D02*
X-93263D01*
G01X-87276Y-303235D02*
X-85318Y-296935D01*
X-83360Y-303235D01*
G01X-84065Y-301030D02*
X-86571D01*
G01X-80820Y-303235D02*
Y-296935D01*
X-77216Y-303235D01*
Y-296935D01*
G01X-68141Y-303235D02*
Y-296935D01*
X-66575D01*
X-65948Y-297250D01*
X-65478Y-297670D01*
X-65086Y-298300D01*
X-64773Y-299035D01*
X-64695Y-300085D01*
X-64773Y-301135D01*
X-65086Y-301870D01*
X-65478Y-302500D01*
X-65948Y-302920D01*
X-66575Y-303235D01*
X-68141D01*
G01X-61058Y-296935D02*
X-59178D01*
G01X-60118D02*
Y-303235D01*
G01X-61058D02*
X-59178D01*
G01X-55463Y-302395D02*
X-54836Y-302920D01*
X-54131Y-303235D01*
X-53505D01*
X-52878Y-302920D01*
X-52408Y-302395D01*
X-52173Y-301660D01*
X-52330Y-300925D01*
X-52721Y-300295D01*
X-53426Y-299875D01*
X-54366Y-299665D01*
X-54915Y-299245D01*
X-55150Y-298510D01*
X-54993Y-297775D01*
X-54601Y-297250D01*
X-54053Y-296935D01*
X-53505D01*
X-52956Y-297145D01*
X-52486Y-297670D01*
G01X-47518Y-296935D02*
Y-303235D01*
G01X-49320Y-296935D02*
X-45716D01*
G01X-41218Y-303445D02*
X-41375Y-303340D01*
Y-303130D01*
X-41218Y-303025D01*
X-41061Y-303130D01*
Y-303340D01*
X-41218Y-303445D01*
G01X-35075Y-304390D02*
X-34761Y-303025D01*
G01X-28618Y-296935D02*
Y-303235D01*
G01X-30420Y-296935D02*
X-26816D01*
G01X-24276Y-303235D02*
X-22318Y-296935D01*
X-20360Y-303235D01*
G01X-21065Y-301030D02*
X-23571D01*
G01X-16018Y-303235D02*
X-16645Y-303130D01*
X-17193Y-302710D01*
X-17663Y-302080D01*
X-17976Y-301345D01*
X-18133Y-300505D01*
Y-299665D01*
X-17976Y-298825D01*
X-17663Y-298090D01*
X-17193Y-297460D01*
X-16645Y-297040D01*
X-16018Y-296935D01*
X-15391Y-297040D01*
X-14843Y-297460D01*
X-14373Y-298090D01*
X-14060Y-298825D01*
X-13903Y-299665D01*
Y-300505D01*
X-14060Y-301345D01*
X-14373Y-302080D01*
X-14843Y-302710D01*
X-15391Y-303130D01*
X-16018Y-303235D01*
G01X-9718D02*
Y-300400D01*
X-11285Y-296935D01*
G01X-8151D02*
X-9718Y-300400D01*
G01X-5141Y-296935D02*
Y-301450D01*
X-4828Y-302395D01*
X-4201Y-303025D01*
X-3418Y-303235D01*
X-2635Y-303025D01*
X-2008Y-302395D01*
X-1695Y-301450D01*
Y-296935D01*
G01X924Y-303235D02*
X2882Y-296935D01*
X4840Y-303235D01*
G01X4135Y-301030D02*
X1629D01*
G01X7380Y-303235D02*
Y-296935D01*
X10984Y-303235D01*
Y-296935D01*
G01X-94518Y-282535D02*
X-97038Y-282118D01*
X-99243Y-280452D01*
X-101133Y-277952D01*
X-102393Y-275035D01*
X-103023Y-271702D01*
Y-268368D01*
X-102393Y-265035D01*
X-101133Y-262118D01*
X-99243Y-259619D01*
X-97038Y-257952D01*
X-94518Y-257535D01*
X-91998Y-257952D01*
X-89793Y-259619D01*
X-87903Y-262118D01*
X-86643Y-265035D01*
X-86013Y-268368D01*
Y-271702D01*
X-86643Y-275035D01*
X-87903Y-277952D01*
X-89793Y-280452D01*
X-91998Y-282118D01*
X-94518Y-282535D01*
G01X-91998Y-275868D02*
X-88218Y-282535D01*
G01X-74673Y-265869D02*
Y-277535D01*
X-73413Y-280452D01*
X-71523Y-282118D01*
X-69318Y-282535D01*
X-67113Y-282118D01*
X-65223Y-280452D01*
X-63963Y-277535D01*
G01Y-282535D02*
Y-265869D01*
G01X-38448Y-282535D02*
Y-265869D01*
G01Y-268785D02*
X-39708Y-267119D01*
X-41598Y-266285D01*
X-43803Y-265869D01*
X-46008Y-266702D01*
X-47898Y-268368D01*
X-49158Y-270869D01*
X-49788Y-274202D01*
X-49158Y-277535D01*
X-47898Y-280036D01*
X-46008Y-281702D01*
X-43803Y-282535D01*
X-41598Y-282118D01*
X-39708Y-280869D01*
X-38448Y-279202D01*
G01X-24273Y-282535D02*
Y-265869D01*
G01Y-270035D02*
X-23013Y-267952D01*
X-21123Y-266285D01*
X-18603Y-265869D01*
X-16398Y-266285D01*
X-14508Y-267952D01*
X-13563Y-270869D01*
Y-282535D01*
G01X6282Y-257535D02*
Y-282535D01*
G01X1872Y-265869D02*
X10692D01*
G01X37152Y-282535D02*
Y-265869D01*
G01Y-268785D02*
X35892Y-267119D01*
X34002Y-266285D01*
X31797Y-265869D01*
X29592Y-266702D01*
X27702Y-268368D01*
X26442Y-270869D01*
X25812Y-274202D01*
X26442Y-277535D01*
X27702Y-280036D01*
X29592Y-281702D01*
X31797Y-282535D01*
X34002Y-282118D01*
X35892Y-280869D01*
X37152Y-279202D01*
G01X9652Y86691D02*
G03X-7480Y58661I14364J-28030D01*
G01D02*
G03X38421Y86670I31496J0D01*
G01X8529Y280867D02*
G03X39950Y255500I5470J-25369D01*
G01X10800Y146000D02*
G03X17600Y141000I6035J1083D01*
G01X17500Y151200D02*
G03X10800Y146000I-585J-6163D01*
G01X14250Y154600D02*
Y152850D01*
G01Y155850D02*
X14350Y155750D01*
Y155650D01*
X14250Y155550D01*
X14150Y155650D01*
Y155750D01*
X14250Y155850D01*
G01X12500Y154050D02*
X12400Y154250D01*
X12300Y154400D01*
X12200Y154500D01*
X12000Y154550D01*
X11850D01*
X11650Y154500D01*
X11500Y154300D01*
X11400Y154100D01*
Y152850D01*
G01X12500Y154550D02*
Y152850D01*
G01X10300Y154500D02*
X9400D01*
G01X9850Y155350D02*
Y152850D01*
X9150Y152900D01*
G01X7150Y154450D02*
X7300Y154500D01*
X7500Y154550D01*
X7650D01*
X7850Y154500D01*
X7950Y154450D01*
X8100Y154350D01*
X8200Y154250D01*
X8300Y154100D01*
X8350Y154000D01*
X8400Y153750D01*
Y153600D01*
X8350Y153400D01*
X8300Y153300D01*
X8200Y153150D01*
X8100Y153050D01*
X7950Y152950D01*
X7850Y152900D01*
X7600Y152850D01*
X7400D01*
X7150Y152950D01*
G01X5450Y155350D02*
Y152850D01*
X4750Y152900D01*
G01X5900Y154500D02*
X5000D01*
G01X25010Y165000D02*
G03I-8010J0D01*
G01X22200Y171000D02*
X11200Y159500D01*
G01X9736Y279449D02*
Y293229D01*
G01X42232Y279449D02*
G02X9736I-16248J0D01*
G01Y293229D02*
G02X42232I16248J0D01*
G01X81647Y147612D02*
G03X81495Y116004I-20658J-15705D01*
G01X16500Y151200D02*
G02X23200Y146000I585J-6163D01*
G01D02*
G02X16400Y141000I-6035J1083D01*
G01X29350Y154950D02*
X29250Y155150D01*
X29150Y155250D01*
X29000Y155350D01*
X28800Y155400D01*
X28550Y155350D01*
X28300Y155100D01*
X28250Y154950D01*
Y154600D01*
X28300Y154450D01*
X28400Y154300D01*
X28500Y154200D01*
X28650Y154100D01*
X28850Y153950D01*
X29000Y153750D01*
X29100Y153650D01*
X29200Y153500D01*
X29300Y153200D01*
X29350Y152850D01*
X28150D01*
G01X27200Y154550D02*
Y152850D01*
G01Y154050D02*
X27100Y154250D01*
X27000Y154400D01*
X26900Y154500D01*
X26700Y154550D01*
X26550D01*
X26350Y154500D01*
X26200Y154300D01*
X26100Y154100D01*
Y152850D01*
G01X23900Y155400D02*
Y152850D01*
G01X25160Y153600D02*
G03I-710J0D01*
G01X23900Y154050D02*
X24000Y154150D01*
X24150Y154250D01*
X24300Y154300D01*
X24550D01*
X24750Y154250D01*
X24900Y154150D01*
X25050Y154000D01*
X25100Y153900D01*
X25150Y153750D01*
Y153550D01*
X25100Y153300D01*
X25000Y153150D01*
X24900Y153050D01*
X24750Y152950D01*
X24600Y152900D01*
X24400D01*
X24150Y152950D01*
X24000Y153050D01*
X23900Y153150D01*
G01X21550Y155450D02*
Y152850D01*
G01X20050Y154550D02*
X19350Y152850D01*
X18650Y154550D01*
G01X17150Y155450D02*
Y152850D01*
G01X39950Y255500D02*
G03X37503Y266501I-25950J0D01*
G01X42232Y293229D02*
Y279449D01*
G01X76832Y-262235D02*
Y-270235D01*
X80832D01*
G01X88632D02*
Y-264902D01*
G01Y-265835D02*
X88232Y-265302D01*
X87632Y-265035D01*
X86932Y-264902D01*
X86232Y-265168D01*
X85632Y-265702D01*
X85232Y-266502D01*
X85032Y-267568D01*
X85232Y-268635D01*
X85632Y-269435D01*
X86232Y-269968D01*
X86932Y-270235D01*
X87632Y-270102D01*
X88232Y-269702D01*
X88632Y-269169D01*
G01X92732Y-272635D02*
X93332Y-272902D01*
X94132Y-272635D01*
X94632Y-272102D01*
X95032Y-271435D01*
X95632Y-269302D01*
X96932Y-264902D01*
G01X93732D02*
X95632Y-269302D01*
G01X101332Y-266635D02*
X104532D01*
X104232Y-265702D01*
X103732Y-265168D01*
X103032Y-264902D01*
X102332Y-265035D01*
X101732Y-265435D01*
X101332Y-266368D01*
X101132Y-267169D01*
Y-267968D01*
X101332Y-268768D01*
X101832Y-269568D01*
X102432Y-270102D01*
X103132Y-270235D01*
X103832Y-269968D01*
X104532Y-269169D01*
G01X109432Y-270235D02*
Y-264902D01*
G01Y-265968D02*
X109932Y-265435D01*
X110432Y-265035D01*
X111132Y-264902D01*
X111632Y-265035D01*
X112232Y-265435D01*
G01X95532Y-320235D02*
Y-312235D01*
X100132Y-320235D01*
Y-312235D01*
G01X105832Y-314902D02*
Y-320235D01*
G01Y-312768D02*
X105632Y-312635D01*
Y-312368D01*
X105832Y-312235D01*
X106032Y-312368D01*
Y-312635D01*
X105832Y-312768D01*
G01X112132Y-320235D02*
Y-314902D01*
G01Y-316235D02*
X112532Y-315568D01*
X113132Y-315035D01*
X113932Y-314902D01*
X114632Y-315035D01*
X115232Y-315568D01*
X115532Y-316502D01*
Y-320235D01*
G01X123632D02*
Y-314902D01*
G01Y-315835D02*
X123232Y-315302D01*
X122632Y-315035D01*
X121932Y-314902D01*
X121232Y-315168D01*
X120632Y-315702D01*
X120232Y-316502D01*
X120032Y-317568D01*
X120232Y-318635D01*
X120632Y-319435D01*
X121232Y-319968D01*
X121932Y-320235D01*
X122632Y-320102D01*
X123232Y-319702D01*
X123632Y-319169D01*
G01X88232Y-294169D02*
X89032Y-294835D01*
X89932Y-295235D01*
X90732D01*
X91532Y-294835D01*
X92132Y-294169D01*
X92432Y-293235D01*
X92232Y-292302D01*
X91732Y-291502D01*
X90832Y-290968D01*
X89632Y-290702D01*
X88932Y-290168D01*
X88632Y-289235D01*
X88832Y-288302D01*
X89332Y-287635D01*
X90032Y-287235D01*
X90732D01*
X91432Y-287502D01*
X92032Y-288168D01*
G01X97132Y-287235D02*
X99532D01*
G01X98332D02*
Y-295235D01*
G01X97132D02*
X99532D01*
G01X104332Y-287235D02*
Y-295235D01*
X108332D01*
G01X112132D02*
Y-287235D01*
G01X115932D02*
X112132Y-292169D01*
G01X116532Y-295235D02*
X113832Y-289902D01*
G01X121032Y-292568D02*
X123632D01*
G01X131132Y-290968D02*
X131532Y-290568D01*
X131832Y-289902D01*
X132032Y-288968D01*
X131832Y-288168D01*
X131432Y-287635D01*
X130732Y-287235D01*
X128032D01*
Y-295235D01*
X131332D01*
X132032Y-294702D01*
X132432Y-293902D01*
X132632Y-292968D01*
X132432Y-292035D01*
X131832Y-291235D01*
X131132Y-290968D01*
X128032D01*
G01X138332Y-295235D02*
X137532Y-295102D01*
X136832Y-294568D01*
X136232Y-293768D01*
X135832Y-292835D01*
X135632Y-291768D01*
Y-290702D01*
X135832Y-289635D01*
X136232Y-288702D01*
X136832Y-287902D01*
X137532Y-287368D01*
X138332Y-287235D01*
X139132Y-287368D01*
X139832Y-287902D01*
X140432Y-288702D01*
X140832Y-289635D01*
X141032Y-290702D01*
Y-291768D01*
X140832Y-292835D01*
X140432Y-293768D01*
X139832Y-294568D01*
X139132Y-295102D01*
X138332Y-295235D01*
G01X146332Y-287235D02*
Y-295235D01*
G01X144032Y-287235D02*
X148632D01*
G01X88136Y107861D02*
X82136D01*
G01D02*
Y113861D01*
G01X91181Y135000D02*
X98681D01*
Y137334D01*
X98306Y138080D01*
X97806Y138547D01*
X96806Y138734D01*
X95806Y138547D01*
X95181Y137987D01*
X94806Y137334D01*
Y135000D01*
G01Y137334D02*
X91181Y138734D01*
G01X94556Y142967D02*
Y145954D01*
X95431Y145674D01*
X95931Y145207D01*
X96181Y144554D01*
X96056Y143900D01*
X95681Y143340D01*
X94806Y142967D01*
X94056Y142780D01*
X93306D01*
X92556Y142967D01*
X91806Y143434D01*
X91306Y143994D01*
X91181Y144647D01*
X91431Y145300D01*
X92181Y145954D01*
G01X96181Y149534D02*
X91181Y150654D01*
X96181Y151867D01*
X91181Y153080D01*
X96181Y154200D01*
G01X91181Y159367D02*
X91306Y158807D01*
X91806Y158247D01*
X92681Y157874D01*
X93681Y157687D01*
X94681Y157874D01*
X95556Y158247D01*
X96056Y158807D01*
X96181Y159367D01*
X96056Y159927D01*
X95556Y160487D01*
X94681Y160860D01*
X93681Y160954D01*
X92681Y160860D01*
X91806Y160487D01*
X91306Y159927D01*
X91181Y159367D01*
G01Y165560D02*
X96181D01*
G01X95181D02*
X95681Y166027D01*
X96056Y166494D01*
X96181Y167147D01*
X96056Y167614D01*
X95681Y168174D01*
G01X91181Y172780D02*
X98681D01*
G01X96181Y175767D02*
X93306Y172780D01*
G01X94431Y173994D02*
X91181Y175954D01*
G01X96181Y187687D02*
X91181Y189367D01*
X96181Y191047D01*
G01X94556Y195467D02*
Y198454D01*
X95431Y198174D01*
X95931Y197707D01*
X96181Y197054D01*
X96056Y196400D01*
X95681Y195840D01*
X94806Y195467D01*
X94056Y195280D01*
X93306D01*
X92556Y195467D01*
X91806Y195934D01*
X91306Y196494D01*
X91181Y197147D01*
X91431Y197800D01*
X92181Y198454D01*
G01X91181Y203060D02*
X96181D01*
G01X95181D02*
X95681Y203527D01*
X96056Y203994D01*
X96181Y204647D01*
X96056Y205114D01*
X95681Y205674D01*
G01X92056Y210467D02*
X91556Y210934D01*
X91181Y211587D01*
Y212147D01*
X91431Y212707D01*
X91806Y213080D01*
X92306Y213267D01*
X93056Y213174D01*
X93431Y212800D01*
X94181Y211120D01*
X95056Y210747D01*
X95681Y210934D01*
X96056Y211307D01*
X96181Y211867D01*
X96056Y212427D01*
X95681Y212987D01*
G01X96181Y219367D02*
X91181D01*
G01X98181D02*
X98306Y219180D01*
X98556D01*
X98681Y219367D01*
X98556Y219554D01*
X98306D01*
X98181Y219367D01*
G01X91181Y226867D02*
X91306Y226307D01*
X91806Y225747D01*
X92681Y225374D01*
X93681Y225187D01*
X94681Y225374D01*
X95556Y225747D01*
X96056Y226307D01*
X96181Y226867D01*
X96056Y227427D01*
X95556Y227987D01*
X94681Y228360D01*
X93681Y228454D01*
X92681Y228360D01*
X91806Y227987D01*
X91306Y227427D01*
X91181Y226867D01*
G01Y232780D02*
X96181D01*
G01X94931D02*
X95556Y233154D01*
X96056Y233714D01*
X96181Y234460D01*
X96056Y235114D01*
X95556Y235674D01*
X94681Y235954D01*
X91181D01*
G01X88136Y263373D02*
X82136D01*
G01D02*
Y257373D01*
G01X119973Y43425D02*
Y57205D01*
G01X152469Y43425D02*
G02X119973I-16248J0D01*
G01Y57205D02*
G02X152469I16248J0D01*
G01X107727Y113861D02*
Y107861D01*
G01D02*
X101727D01*
G01X159966Y147928D02*
G03I-25950J0D01*
G01X108663Y223606D02*
G03X129499Y216049I20470J23937D01*
G01X107727Y257373D02*
Y263373D01*
G01D02*
X101727D01*
G01X114770Y275573D02*
G03X102425Y264235I14364J-28030D01*
G01X134584Y216522D02*
G03X145441Y220597I-5450J31021D01*
G01X152469Y57205D02*
Y43425D01*
G01X149740Y223723D02*
G03X143539Y275552I-20606J23820D01*
G01X203432Y-313568D02*
X204032Y-312768D01*
X204732Y-312368D01*
X205532Y-312235D01*
X206532Y-312502D01*
X207232Y-313168D01*
X207432Y-313968D01*
X207332Y-314769D01*
X206932Y-315435D01*
X204932Y-316768D01*
X204032Y-317702D01*
X203432Y-319035D01*
X203232Y-320235D01*
X207432D01*
G01X213332Y-312235D02*
X212532Y-312502D01*
X211932Y-313168D01*
X211532Y-313968D01*
X211232Y-315035D01*
X211132Y-316235D01*
X211232Y-317435D01*
X211532Y-318502D01*
X211932Y-319302D01*
X212532Y-319968D01*
X213332Y-320235D01*
X214132Y-319968D01*
X214732Y-319302D01*
X215132Y-318502D01*
X215432Y-317435D01*
X215532Y-316235D01*
X215432Y-315035D01*
X215132Y-313968D01*
X214732Y-313168D01*
X214132Y-312502D01*
X213332Y-312235D01*
G01X219432Y-313568D02*
X220032Y-312768D01*
X220732Y-312368D01*
X221532Y-312235D01*
X222532Y-312502D01*
X223232Y-313168D01*
X223432Y-313968D01*
X223332Y-314769D01*
X222932Y-315435D01*
X220932Y-316768D01*
X220032Y-317702D01*
X219432Y-319035D01*
X219232Y-320235D01*
X223432D01*
G01X227432Y-313568D02*
X228032Y-312768D01*
X228732Y-312368D01*
X229532Y-312235D01*
X230532Y-312502D01*
X231232Y-313168D01*
X231432Y-313968D01*
X231332Y-314769D01*
X230932Y-315435D01*
X228932Y-316768D01*
X228032Y-317702D01*
X227432Y-319035D01*
X227232Y-320235D01*
X231432D01*
G01X235532Y-320502D02*
X239132Y-312235D01*
G01X245332Y-320235D02*
Y-312235D01*
X244132Y-313835D01*
G01Y-320235D02*
X246532D01*
G01X251432Y-313568D02*
X252032Y-312768D01*
X252732Y-312368D01*
X253532Y-312235D01*
X254532Y-312502D01*
X255232Y-313168D01*
X255432Y-313968D01*
X255332Y-314769D01*
X254932Y-315435D01*
X252932Y-316768D01*
X252032Y-317702D01*
X251432Y-319035D01*
X251232Y-320235D01*
X255432D01*
G01X259532Y-320502D02*
X263132Y-312235D01*
G01X269332D02*
X268532Y-312502D01*
X267932Y-313168D01*
X267532Y-313968D01*
X267232Y-315035D01*
X267132Y-316235D01*
X267232Y-317435D01*
X267532Y-318502D01*
X267932Y-319302D01*
X268532Y-319968D01*
X269332Y-320235D01*
X270132Y-319968D01*
X270732Y-319302D01*
X271132Y-318502D01*
X271432Y-317435D01*
X271532Y-316235D01*
X271432Y-315035D01*
X271132Y-313968D01*
X270732Y-313168D01*
X270132Y-312502D01*
X269332Y-312235D01*
G01X275632Y-319302D02*
X276332Y-319968D01*
X277132Y-320235D01*
X277932Y-319968D01*
X278632Y-319169D01*
X279132Y-317968D01*
X279332Y-316768D01*
Y-315302D01*
X279132Y-314102D01*
X278632Y-313035D01*
X278032Y-312502D01*
X277332Y-312235D01*
X276532Y-312502D01*
X275932Y-313035D01*
X275532Y-313835D01*
X275332Y-314902D01*
X275532Y-315835D01*
X276032Y-316768D01*
X276632Y-317302D01*
X277332Y-317435D01*
X278132Y-317169D01*
X278732Y-316502D01*
X279332Y-315302D01*
G01X205632Y-295235D02*
Y-287235D01*
X207632D01*
X208432Y-287635D01*
X209032Y-288168D01*
X209532Y-288968D01*
X209932Y-289902D01*
X210032Y-291235D01*
X209932Y-292568D01*
X209532Y-293502D01*
X209032Y-294302D01*
X208432Y-294835D01*
X207632Y-295235D01*
X205632D01*
G01X213332D02*
X215832Y-287235D01*
X218332Y-295235D01*
G01X217432Y-292435D02*
X214232D01*
G01X223832Y-287235D02*
X223032Y-287502D01*
X222432Y-288168D01*
X222032Y-288968D01*
X221732Y-290035D01*
X221632Y-291235D01*
X221732Y-292435D01*
X222032Y-293502D01*
X222432Y-294302D01*
X223032Y-294968D01*
X223832Y-295235D01*
X224632Y-294968D01*
X225232Y-294302D01*
X225632Y-293502D01*
X225932Y-292435D01*
X226032Y-291235D01*
X225932Y-290035D01*
X225632Y-288968D01*
X225232Y-288168D01*
X224632Y-287502D01*
X223832Y-287235D01*
G01X229932Y-295235D02*
Y-287235D01*
X233732D01*
G01X232332Y-291102D02*
X229932D01*
G01X239832Y-287235D02*
X239032Y-287502D01*
X238432Y-288168D01*
X238032Y-288968D01*
X237732Y-290035D01*
X237632Y-291235D01*
X237732Y-292435D01*
X238032Y-293502D01*
X238432Y-294302D01*
X239032Y-294968D01*
X239832Y-295235D01*
X240632Y-294968D01*
X241232Y-294302D01*
X241632Y-293502D01*
X241932Y-292435D01*
X242032Y-291235D01*
X241932Y-290035D01*
X241632Y-288968D01*
X241232Y-288168D01*
X240632Y-287502D01*
X239832Y-287235D01*
G01X247832D02*
Y-295235D01*
G01X245532Y-287235D02*
X250132D01*
G01X255832Y-295235D02*
Y-291635D01*
X253832Y-287235D01*
G01X257832D02*
X255832Y-291635D01*
G01X264632Y-290968D02*
X265032Y-290568D01*
X265332Y-289902D01*
X265532Y-288968D01*
X265332Y-288168D01*
X264932Y-287635D01*
X264232Y-287235D01*
X261532D01*
Y-295235D01*
X264832D01*
X265532Y-294702D01*
X265932Y-293902D01*
X266132Y-292968D01*
X265932Y-292035D01*
X265332Y-291235D01*
X264632Y-290968D01*
X261532D01*
G01X273032Y-295235D02*
Y-287235D01*
X269332Y-292968D01*
X274332D01*
G01X277632Y-295235D02*
Y-287235D01*
X279632D01*
X280432Y-287635D01*
X281032Y-288168D01*
X281532Y-288968D01*
X281932Y-289902D01*
X282032Y-291235D01*
X281932Y-292568D01*
X281532Y-293502D01*
X281032Y-294302D01*
X280432Y-294835D01*
X279632Y-295235D01*
X277632D01*
G01X287832Y-287235D02*
X287032Y-287502D01*
X286432Y-288168D01*
X286032Y-288968D01*
X285732Y-290035D01*
X285632Y-291235D01*
X285732Y-292435D01*
X286032Y-293502D01*
X286432Y-294302D01*
X287032Y-294968D01*
X287832Y-295235D01*
X288632Y-294968D01*
X289232Y-294302D01*
X289632Y-293502D01*
X289932Y-292435D01*
X290032Y-291235D01*
X289932Y-290035D01*
X289632Y-288968D01*
X289232Y-288168D01*
X288632Y-287502D01*
X287832Y-287235D01*
G01X233432Y-270235D02*
Y-262235D01*
X237232D01*
G01X235832Y-266102D02*
X233432D01*
G01X243332Y-262235D02*
X242532Y-262502D01*
X241932Y-263168D01*
X241532Y-263968D01*
X241232Y-265035D01*
X241132Y-266235D01*
X241232Y-267435D01*
X241532Y-268502D01*
X241932Y-269302D01*
X242532Y-269968D01*
X243332Y-270235D01*
X244132Y-269968D01*
X244732Y-269302D01*
X245132Y-268502D01*
X245432Y-267435D01*
X245532Y-266235D01*
X245432Y-265035D01*
X245132Y-263968D01*
X244732Y-263168D01*
X244132Y-262502D01*
X243332Y-262235D01*
G01X251332D02*
Y-270235D01*
G01X249032Y-262235D02*
X253632D01*
G01X256332Y-272902D02*
X262332D01*
G01X265332Y-270235D02*
Y-262235D01*
X267732D01*
X268532Y-262635D01*
X269132Y-263568D01*
X269332Y-264635D01*
X269132Y-265702D01*
X268632Y-266502D01*
X267732Y-266902D01*
X265332D01*
G01X272832Y-270235D02*
X275332Y-262235D01*
X277832Y-270235D01*
G01X276932Y-267435D02*
X273732D01*
G01X281032Y-270235D02*
Y-262235D01*
X285632Y-270235D01*
Y-262235D01*
G01X293332Y-270235D02*
X289332D01*
Y-262235D01*
X293332D01*
G01X291732Y-266102D02*
X289332D01*
G01X297332Y-262235D02*
Y-270235D01*
X301332D01*
G01X304332Y-272902D02*
X310332D01*
G01X316132Y-265968D02*
X316532Y-265568D01*
X316832Y-264902D01*
X317032Y-263968D01*
X316832Y-263168D01*
X316432Y-262635D01*
X315732Y-262235D01*
X313032D01*
Y-270235D01*
X316332D01*
X317032Y-269702D01*
X317432Y-268902D01*
X317632Y-267968D01*
X317432Y-267035D01*
X316832Y-266235D01*
X316132Y-265968D01*
X313032D01*
G01X321132Y-270235D02*
Y-262235D01*
X323132D01*
X323932Y-262635D01*
X324532Y-263168D01*
X325032Y-263968D01*
X325432Y-264902D01*
X325532Y-266235D01*
X325432Y-267568D01*
X325032Y-268502D01*
X324532Y-269302D01*
X323932Y-269835D01*
X323132Y-270235D01*
X321132D01*
G01X291832Y-323235D02*
Y-315235D01*
X290632Y-316835D01*
G01Y-323235D02*
X293032D01*
G01X297932Y-319902D02*
X298632Y-318968D01*
X299232Y-318435D01*
X300032Y-318168D01*
X300732Y-318435D01*
X301232Y-318968D01*
X301632Y-319768D01*
X301732Y-320702D01*
X301632Y-321502D01*
X301232Y-322302D01*
X300632Y-322968D01*
X299932Y-323235D01*
X299132Y-322968D01*
X298432Y-322169D01*
X298032Y-320968D01*
X297932Y-319635D01*
X298132Y-317902D01*
X298432Y-316968D01*
X298932Y-316035D01*
X299632Y-315368D01*
X300332Y-315235D01*
X301032Y-315502D01*
X301532Y-316168D01*
G01X307832Y-323502D02*
X307632Y-323368D01*
Y-323102D01*
X307832Y-322968D01*
X308032Y-323102D01*
Y-323368D01*
X307832Y-323502D01*
G01X313932Y-319902D02*
X314632Y-318968D01*
X315232Y-318435D01*
X316032Y-318168D01*
X316732Y-318435D01*
X317232Y-318968D01*
X317632Y-319768D01*
X317732Y-320702D01*
X317632Y-321502D01*
X317232Y-322302D01*
X316632Y-322968D01*
X315932Y-323235D01*
X315132Y-322968D01*
X314432Y-322169D01*
X314032Y-320968D01*
X313932Y-319635D01*
X314132Y-317902D01*
X314432Y-316968D01*
X314932Y-316035D01*
X315632Y-315368D01*
X316332Y-315235D01*
X317032Y-315502D01*
X317532Y-316168D01*
G01X336832Y-323235D02*
Y-315235D01*
X335632Y-316835D01*
G01Y-323235D02*
X338032D01*
G01X344632D02*
X344832Y-321502D01*
X345132Y-320035D01*
X345532Y-318702D01*
X346032Y-317235D01*
X346832Y-315235D01*
X342832D01*
G01X352832Y-323502D02*
X352632Y-323368D01*
Y-323102D01*
X352832Y-322968D01*
X353032Y-323102D01*
Y-323368D01*
X352832Y-323502D01*
G01X358932Y-316568D02*
X359532Y-315768D01*
X360232Y-315368D01*
X361032Y-315235D01*
X362032Y-315502D01*
X362732Y-316168D01*
X362932Y-316968D01*
X362832Y-317769D01*
X362432Y-318435D01*
X360432Y-319768D01*
X359532Y-320702D01*
X358932Y-322035D01*
X358732Y-323235D01*
X362932D01*
G01X356632Y-298235D02*
Y-290235D01*
X358632D01*
X359432Y-290635D01*
X360032Y-291168D01*
X360532Y-291968D01*
X360932Y-292902D01*
X361032Y-294235D01*
X360932Y-295568D01*
X360532Y-296502D01*
X360032Y-297302D01*
X359432Y-297835D01*
X358632Y-298235D01*
X356632D01*
M02*
